FILE_TYPE = CONNECTIVITY;
{Allegro Design Entry HDL 16.6-p007 (v16-6-112F) 10/10/2012}
"PAGE_NUMBER" = 96;
0"NC";
1"PVCCIO_CPU0\g";
2"PVCCIO_CPU1\g";
3"PVDDQ_KLM\g";
4"PVDDQ_GHJ\g";
5"PVDDQ_DEF\g";
6"GND\g";
7"GND\g";
8"PVDDQ_ABC\g";
9"P3V3_STBY\g";
10"P3V3_STBY\g";
11"GND\g";
12"GND\g";
13"GND\g";
14"GND\g";
15"PWRGD_CPU0_DRAMPWROK_ABC_G";
16"PWRGD_CPU0_DRAMPWROK_DEF_G";
17"PWRGD_CPU0_G";
18"RST_CPU0_G_N";
19"PD_GTL2014_1_VREF";
20"PU_GTL2014_2_DIR";
21"PD_GTL2014_2_VREF";
22"RST_CPU0_LVC3_N";
23"PWRGD_CPU1_LVC3";
24"RST_CPU1_LVC3_N";
25"PWRGD_DRAMPWRGD";
26"PWRGD_DRAMPWRGD";
27"PU_GTL2014_1_DIR";
28"PWRGD_CPU0_LVC3";
29"RST_CPU1_G_N";
30"PWRGD_CPU1_DRAMPWROK_KLM_G";
31"PWRGD_CPU1_DRAMPWROK_GHJ_G";
32"PWRGD_CPU1_G";
%"PVCCIO_CPU0"
"1","(1800,4700)","0","mstr_symbols","I1";
;
VOLTAGE"1.1V"
CDS_LIB"mstr_symbols"
BODY_TYPE"PLUMBING"
HDL_POWER"PVCCIO_CPU0";
"G\NAC"1;
%"RES"
"2","(1900,4450)","0","mstr_discrete","I2";
;
CDS_SEC"1"
LOCATION"R6D12"
PART_NUMBER"G21796-047"
VALUE"49.9"
TOLERANCE"1%"
PACK_TYPE"0402"
MATERIAL"CHIP"
WATTAGE"1/16W"
BOM_COST"PROC_SIDEBAND"
CDS_LIB"mstr_discrete"
SEC_TYPE"0402"
SEC"1"
CDS_LOCATION"R6D12"
ROOM"PROC_RSTS_PGOODS";
"A"
$PN"1"1;
"B"
$PN"2"18;
%"PVCCIO_CPU1"
"1","(1800,2425)","0","mstr_symbols","I24";
;
VOLTAGE"1.1V"
CDS_LIB"mstr_symbols"
BODY_TYPE"PLUMBING"
HDL_POWER"PVCCIO_CPU1";
"G\NAC"2;
%"RES"
"2","(1900,2150)","0","mstr_discrete","I25";
;
CDS_SEC"1"
LOCATION"R3D20"
PART_NUMBER"G21796-047"
VALUE"49.9"
TOLERANCE"1%"
PACK_TYPE"0402"
MATERIAL"CHIP"
WATTAGE"1/16W"
BOM_COST"PROC_SIDEBAND"
CDS_LIB"mstr_discrete"
SEC_TYPE"0402"
SEC"1"
CDS_LOCATION"R3D20"
ROOM"PROC_RSTS_PGOODS";
"A"
$PN"1"2;
"B"
$PN"2"29;
%"RES"
"2","(1700,2150)","2","mstr_discrete","I26";
;
CDS_SEC"1"
LOCATION"R3D15"
PART_NUMBER"G21796-047"
VALUE"49.9"
TOLERANCE"1%"
PACK_TYPE"0402"
MATERIAL"CHIP"
WATTAGE"1/16W"
BOM_COST"PROC_SIDEBAND"
CDS_LIB"mstr_discrete"
SEC_TYPE"0402"
SEC"1"
CDS_LOCATION"R3D15"
ROOM"PROC_RSTS_PGOODS";
"A"
$PN"1"2;
"B"
$PN"2"32;
%"PVDDQ_KLM"
"1","(975,2400)","0","mstr_symbols","I27";
;
VOLTAGE"1.2V"
CDS_LIB"mstr_symbols"
BODY_TYPE"PLUMBING"
HDL_POWER"PVDDQ_KLM";
"G\NAC"3;
%"RES"
"2","(975,2150)","0","mstr_discrete","I28";
;
LOCATION"R7M9"
PART_NUMBER"G21796-298"
VALUE"64.9"
TOLERANCE"1.0%"
PACK_TYPE"0402"
MATERIAL"CHIP"
WATTAGE"1/16W"
BOM_COST"PROC_SIDEBAND"
CDS_LIB"mstr_discrete"
CDS_SEC"1"
$SEC"1"
CDS_LOCATION"R7M9"
ROOM"PROC_RSTS_PGOODS";
"A"
$PN"1"3;
"B"
$PN"2"30;
%"PVDDQ_GHJ"
"1","(575,2400)","0","mstr_symbols","I29";
;
VOLTAGE"1.2V"
CDS_LIB"mstr_symbols"
BODY_TYPE"PLUMBING"
HDL_POWER"PVDDQ_GHJ";
"G\NAC"4;
%"RES"
"2","(1700,4450)","2","mstr_discrete","I3";
;
CDS_SEC"1"
LOCATION"R6D8"
PART_NUMBER"G21796-047"
VALUE"49.9"
TOLERANCE"1%"
PACK_TYPE"0402"
MATERIAL"CHIP"
WATTAGE"1/16W"
BOM_COST"PROC_SIDEBAND"
CDS_LIB"mstr_discrete"
SEC_TYPE"0402"
SEC"1"
CDS_LOCATION"R6D8"
ROOM"PROC_RSTS_PGOODS";
"A"
$PN"1"1;
"B"
$PN"2"17;
%"RES"
"2","(575,2150)","0","mstr_discrete","I30";
;
LOCATION"R3D21"
PART_NUMBER"G21796-298"
VALUE"64.9"
TOLERANCE"1.0%"
PACK_TYPE"0402"
MATERIAL"CHIP"
WATTAGE"1/16W"
BOM_COST"PROC_SIDEBAND"
CDS_LIB"mstr_discrete"
CDS_SEC"1"
$SEC"1"
CDS_LOCATION"R3D21"
ROOM"PROC_RSTS_PGOODS";
"A"
$PN"1"4;
"B"
$PN"2"31;
%"RES"
"2","(-2100,4650)","0","mstr_discrete","I36";
;
LOCATION"R3P36"
PACK_TYPE"0402"
PART_NUMBER"G21796-026"
VALUE"1.00K"
TOLERANCE"1%"
MATERIAL"CHIP"
WATTAGE"1/16W"
BOM_COST"PROC_SIDEBAND"
CDS_LIB"mstr_discrete"
CDS_SEC"1"
$SEC"1"
CDS_LOCATION"R3P36"
ROOM"PROC_RSTS_PGOODS";
"A"
$PN"1"10;
"B"
$PN"2"27;
%"PVDDQ_DEF"
"1","(975,4700)","0","mstr_symbols","I4";
;
VOLTAGE"1.2V"
CDS_LIB"mstr_symbols"
BODY_TYPE"PLUMBING"
HDL_POWER"PVDDQ_DEF";
"G\NAC"5;
%"GND"
"1","(-325,3550)","0","mstr_symbols","I41";
;
VOLTAGE"0.0V"
SIZE"1B"
CDS_LIB"mstr_symbols"
BODY_TYPE"PLUMBING"
HDL_POWER"GND";
"A\NAC"6;
%"GTL2014"
"1","(-875,4100)","0","mstr_digital","I42";
;
LOCATION"U3P1"
MATERIAL"IC"
PART_NUMBER"D66151-001"
PACK_TYPE"SM"
BOM_COST"PROC_SIDEBAND"
CDS_LIB"mstr_digital"
CDS_SEC"1"
$SEC"1"
CDS_LOCATION"U3P1"
ROOM"PROC_RSTS_PGOODS";
"A0"
$PN"13"26;
"A1"
$PN"12"26;
"A3"
$PN"9"28;
"A2"
$PN"10"22;
"B2"
$PN"5"18;
"B3"
$PN"6"17;
"B0"
$PN"2"16;
"B1"
$PN"3"15;
"GND<1>"
$PN"8"6;
"GND<2>"
$PN"11"6;
"GND<0>"
$PN"7"6;
"VCC"
$PN"14"10;
"VREF"
$PN"4"19;
"DIR"
$PN"1"27;
%"GND"
"1","(-325,1250)","0","mstr_symbols","I45";
;
VOLTAGE"0.0V"
CDS_LIB"mstr_symbols"
SIZE"1B"
BODY_TYPE"PLUMBING"
HDL_POWER"GND";
"A\NAC"7;
%"GTL2014"
"1","(-875,1800)","0","mstr_digital","I46";
;
LOCATION"U4C2"
PART_NUMBER"D66151-001"
MATERIAL"IC"
PACK_TYPE"SM"
CDS_LIB"mstr_digital"
BOM_COST"PROC_SIDEBAND"
CDS_SEC"1"
$SEC"1"
CDS_LOCATION"U4C2"
ROOM"PROC_RSTS_PGOODS";
"A0"
$PN"13"25;
"A1"
$PN"12"25;
"A3"
$PN"9"23;
"A2"
$PN"10"24;
"B2"
$PN"5"29;
"B3"
$PN"6"32;
"B0"
$PN"2"30;
"B1"
$PN"3"31;
"GND<1>"
$PN"8"7;
"GND<2>"
$PN"11"7;
"GND<0>"
$PN"7"7;
"VCC"
$PN"14"9;
"VREF"
$PN"4"21;
"DIR"
$PN"1"20;
%"RES"
"2","(975,4450)","0","mstr_discrete","I5";
;
LOCATION"R3P29"
PART_NUMBER"G21796-298"
VALUE"64.9"
TOLERANCE"1.0%"
PACK_TYPE"0402"
MATERIAL"CHIP"
WATTAGE"1/16W"
BOM_COST"PROC_SIDEBAND"
CDS_LIB"mstr_discrete"
CDS_SEC"1"
$SEC"1"
CDS_LOCATION"R3P29"
ROOM"PROC_RSTS_PGOODS";
"A"
$PN"1"5;
"B"
$PN"2"16;
%"RES"
"2","(-2100,2350)","0","mstr_discrete","I55";
;
LOCATION"R4C8"
PART_NUMBER"G21796-026"
VALUE"1.00K"
TOLERANCE"1%"
PACK_TYPE"0402"
MATERIAL"CHIP"
WATTAGE"1/16W"
BOM_COST"PROC_SIDEBAND"
CDS_LIB"mstr_discrete"
CDS_SEC"1"
$SEC"1"
CDS_LOCATION"R4C8"
ROOM"PROC_RSTS_PGOODS";
"A"
$PN"1"9;
"B"
$PN"2"20;
%"PVDDQ_ABC"
"1","(575,4700)","0","mstr_symbols","I6";
;
VOLTAGE"1.2V"
CDS_LIB"mstr_symbols"
BODY_TYPE"PLUMBING"
HDL_POWER"PVDDQ_ABC";
"G\NAC"8;
%"P3V3_STBY"
"1","(-2100,2725)","0","mstr_symbols","I65";
;
VOLTAGE"3.3V"
CDS_LIB"mstr_symbols"
SIZE"1B"
BODY_TYPE"PLUMBING"
HDL_POWER"P3V3_STBY";
"G\NAC"9;
%"P3V3_STBY"
"1","(-2100,5050)","0","mstr_symbols","I68";
;
VOLTAGE"3.3V"
SIZE"1B"
CDS_LIB"mstr_symbols"
BODY_TYPE"PLUMBING"
HDL_POWER"P3V3_STBY";
"G\NAC"10;
%"RES"
"1","(-2400,2050)","0","mstr_discrete","I69";
;
CDS_SEC"1"
LOCATION"R4C9"
PART_NUMBER"G21796-026"
VALUE"1.00K"
TOLERANCE"1%"
PACK_TYPE"0402"
MATERIAL"CHIP"
WATTAGE"1/16W"
BOM_COST"PROC_SIDEBAND"
SEC_TYPE"0402"
CDS_LIB"mstr_discrete"
SEC"1"
CDS_LOCATION"R4C9"
ROOM"PROC_RSTS_PGOODS";
"B"
$PN"2"21;
"A"
$PN"1"11;
%"RES"
"2","(575,4450)","0","mstr_discrete","I7";
;
LOCATION"R3P38"
PART_NUMBER"G21796-298"
VALUE"64.9"
TOLERANCE"1.0%"
PACK_TYPE"0402"
MATERIAL"CHIP"
WATTAGE"1/16W"
BOM_COST"PROC_SIDEBAND"
CDS_LIB"mstr_discrete"
CDS_SEC"1"
$SEC"1"
CDS_LOCATION"R3P38"
ROOM"PROC_RSTS_PGOODS";
"A"
$PN"1"8;
"B"
$PN"2"15;
%"GND"
"1","(-2875,1950)","0","mstr_symbols","I70";
;
VOLTAGE"0.0V"
CDS_LIB"mstr_symbols"
SIZE"1B"
BODY_TYPE"PLUMBING"
HDL_POWER"GND";
"A\NAC"11;
%"RES"
"1","(-2400,4350)","0","mstr_discrete","I71";
;
CDS_SEC"1"
LOCATION"R3P32"
VALUE"1.00K"
TOLERANCE"1%"
PACK_TYPE"0402"
MATERIAL"CHIP"
WATTAGE"1/16W"
PART_NUMBER"G21796-026"
BOM_COST"PROC_SIDEBAND"
SEC_TYPE"0402"
CDS_LIB"mstr_discrete"
SEC"1"
CDS_LOCATION"R3P32"
ROOM"PROC_RSTS_PGOODS";
"B"
$PN"2"19;
"A"
$PN"1"12;
%"GND"
"1","(-2775,4225)","0","mstr_symbols","I72";
;
VOLTAGE"0.0V"
SIZE"1B"
CDS_LIB"mstr_symbols"
BODY_TYPE"PLUMBING"
HDL_POWER"GND";
"A\NAC"12;
%"CAP_A"
"1","(-1650,4650)","0","dev_discrete","I73";
;
LOCATION"C3P42"
PART_NUMBER"D97712-004"
VALUE"1.0UF"
TOLERANCE"10%"
PACK_TYPE"0402V"
VOLTAGE"6.3V"
MATERIAL"X6S"
CDS_LOCATION"C3P42"
BOM_COST"PROC_SIDEBAND"
CDS_LIB"dev_discrete"
CDS_SEC"1"
SEC_TYPE"0402V"
SEC"1"
ROOM"PROC_RSTS_PGOODS";
"B"
$PN"2"13;
"A"
$PN"1"10;
%"GND"
"1","(-1650,4450)","0","mstr_symbols","I74";
;
VOLTAGE"0.0V"
CDS_LIB"mstr_symbols"
SIZE"1B"
BODY_TYPE"PLUMBING"
HDL_POWER"GND";
"A\NAC"13;
%"CAP_A"
"1","(-1725,2325)","0","dev_discrete","I75";
;
LOCATION"C4C3"
PART_NUMBER"D97712-004"
VALUE"1.0UF"
TOLERANCE"10%"
PACK_TYPE"0402V"
VOLTAGE"6.3V"
MATERIAL"X6S"
CDS_LOCATION"C4C3"
BOM_COST"PROC_SIDEBAND"
CDS_LIB"dev_discrete"
CDS_SEC"1"
SEC_TYPE"0402V"
SEC"1"
ROOM"PROC_RSTS_PGOODS";
"B"
$PN"2"14;
"A"
$PN"1"9;
%"GND"
"1","(-1725,2125)","0","mstr_symbols","I76";
;
VOLTAGE"0.0V"
CDS_LIB"mstr_symbols"
SIZE"1B"
BODY_TYPE"PLUMBING"
HDL_POWER"GND";
"A\NAC"14;
END.
